# T6G (Grand Teton) — schematic netlist excerpt (pin names and nets, part order shuffled) for the footprints in the layout excerpt that follows; sources: Cadence DE-HDL packaged netlist, KiCad conversion of 04192023_DAF0TMB3IC0_F0TG_MB_C_brd_V02_OCP.brd

R597  Q_RES  0 5% CHIP  pkg 0201LF  page 331 : A = CLK_100M_RETIMER_CPU1_P1_R_DP ; B = CLK_100M_RETIMER_CPU1_P1_DP
C3930  Q_CAP  22UF 4V 20% X6S  pkg C0402  page 70 : A = PVDDCR_SOC_P0 ; B = GND
R3779  Q_RES  0 5% CHIP  pkg 0402LF  page 145 : A = RST_PERST_E1S_0_N ; B = RST_PCIE_E1S_PERST_N

(kicad_pcb
	(version 20260206)
	(generator "pcbnew")
	(generator_version "10.0")
	(general
		(thickness 1.6)
		(legacy_teardrops no)
	)
	(paper "A4")
	(title_block
		(title "04192023_DAF0TMB3IC0_F0TG_MB_C_brd_V02_OCP.brd")
		(comment 1 "Grand Teton / footprints 1527-1529 of 8354")
	)
	(layers
		(0 "F.Cu" signal "TOP")
		(4 "In1.Cu" signal "GND")
		(6 "In2.Cu" signal "IN1")
		(8 "In3.Cu" signal "GND1")
		(10 "In4.Cu" signal "IN2")
		(12 "In5.Cu" signal "GND2")
		(14 "In6.Cu" signal "IN3")
		(16 "In7.Cu" signal "GND3")
		(18 "In8.Cu" signal "VCC")
		(20 "In9.Cu" signal "VCC1")
		(22 "In10.Cu" signal "GND4")
		(24 "In11.Cu" signal "IN4")
		(26 "In12.Cu" signal "GND5")
		(28 "In13.Cu" signal "IN5")
		(30 "In14.Cu" signal "GND6")
		(32 "In15.Cu" signal "IN6")
		(34 "In16.Cu" signal "GND7")
		(2 "B.Cu" signal "BOTTOM")
		(9 "F.Adhes" user "F.Adhesive")
		(11 "B.Adhes" user "B.Adhesive")
		(13 "F.Paste" user "Package Geometry/Pastemask Top")
		(15 "B.Paste" user "Package Geometry/Pastemask Bottom")
		(5 "F.SilkS" user "Ref Des/Silkscreen Top")
		(7 "B.SilkS" user "Ref Des/Silkscreen Bottom")
		(1 "F.Mask" user "Board Geometry/Soldermask Top")
		(3 "B.Mask" user "Board Geometry/Soldermask Bottom")
		(17 "Dwgs.User" user "User.Drawings")
		(19 "Cmts.User" user "User.Comments")
		(21 "Eco1.User" user "User.Eco1")
		(23 "Eco2.User" user "User.Eco2")
		(25 "Edge.Cuts" user "Board Geometry/Outline")
		(27 "Margin" user)
		(31 "F.CrtYd" user "Package Geometry/Place Bound Top")
		(29 "B.CrtYd" user "Package Geometry/Place Bound Bottom")
		(35 "F.Fab" user "Ref Des/Assembly Top")
		(33 "B.Fab" user "Ref Des/Assembly Bottom")
	)
	(footprint ""
		(layer "F.Cu")
		(at 357.515922 -256.012188 90)
		(property "Reference" "C3930"
			(at 0 0 90)
			(layer "F.SilkS")
			(hide yes)
			(effects
				(font
					(size 1.27 1.27)
				)
			)
		)
		(property "Value" ""
			(at 0 0 90)
			(layer "F.Fab")
			(effects
				(font
					(size 1.27 1.27)
				)
			)
		)
		(duplicate_pad_numbers_are_jumpers no)
		(fp_line
			(start 0.7874 -0.4064)
			(end 0.7874 0.4064)
			(stroke
				(width 0.1524)
				(type default)
			)
			(layer "F.SilkS")
		)
		(fp_line
			(start -0.7874 -0.4064)
			(end 0.7874 -0.4064)
			(stroke
				(width 0.1524)
				(type default)
			)
			(layer "F.SilkS")
		)
		(fp_line
			(start 0.7874 0.4064)
			(end -0.7874 0.4064)
			(stroke
				(width 0.1524)
				(type default)
			)
			(layer "F.SilkS")
		)
		(fp_line
			(start -0.7874 0.4064)
			(end -0.7874 -0.4064)
			(stroke
				(width 0.1524)
				(type default)
			)
			(layer "F.SilkS")
		)
		(fp_line
			(start -0.12065 -0.305054)
			(end -0.12065 -0.2794)
			(stroke
				(width 0.1)
				(type default)
			)
			(layer "F.Fab")
		)
		(fp_line
			(start -0.67945 -0.305054)
			(end -0.12065 -0.305054)
			(stroke
				(width 0.1)
				(type default)
			)
			(layer "F.Fab")
		)
		(fp_line
			(start 0.67945 -0.3048)
			(end 0.67945 0.3048)
			(stroke
				(width 0.1)
				(type default)
			)
			(layer "F.Fab")
		)
		(fp_line
			(start 0.12065 -0.3048)
			(end 0.67945 -0.3048)
			(stroke
				(width 0.1)
				(type default)
			)
			(layer "F.Fab")
		)
		(fp_line
			(start 0.12065 -0.2794)
			(end 0.12065 -0.3048)
			(stroke
				(width 0.1)
				(type default)
			)
			(layer "F.Fab")
		)
		(fp_line
			(start -0.12065 -0.2794)
			(end 0.12065 -0.2794)
			(stroke
				(width 0.1)
				(type default)
			)
			(layer "F.Fab")
		)
		(fp_line
			(start 0.120396 0.2794)
			(end -0.12065 0.2794)
			(stroke
				(width 0.1)
				(type default)
			)
			(layer "F.Fab")
		)
		(fp_line
			(start -0.12065 0.2794)
			(end -0.12065 0.3048)
			(stroke
				(width 0.1)
				(type default)
			)
			(layer "F.Fab")
		)
		(fp_line
			(start 0.67945 0.3048)
			(end 0.120396 0.3048)
			(stroke
				(width 0.1)
				(type default)
			)
			(layer "F.Fab")
		)
		(fp_line
			(start 0.120396 0.3048)
			(end 0.120396 0.2794)
			(stroke
				(width 0.1)
				(type default)
			)
			(layer "F.Fab")
		)
		(fp_line
			(start -0.12065 0.3048)
			(end -0.67945 0.3048)
			(stroke
				(width 0.1)
				(type default)
			)
			(layer "F.Fab")
		)
		(fp_line
			(start -0.67945 0.3048)
			(end -0.67945 -0.305054)
			(stroke
				(width 0.1)
				(type default)
			)
			(layer "F.Fab")
		)
		(pad "1" smd circle
			(at -0.40005 0 90)
			(size 0 0)
			(layers "F.Cu" "F.Mask" "F.Paste")
			(net "PVDDCR_SOC_P0")
		)
		(pad "2" smd circle
			(at 0.40005 0 90)
			(size 0 0)
			(layers "F.Cu" "F.Mask" "F.Paste")
			(net "GND")
		)
	)
	(footprint ""
		(layer "F.Cu")
		(at 75.05573 -387.764274)
		(property "Reference" "R597"
			(at 0 0 0)
			(layer "F.SilkS")
			(hide yes)
			(effects
				(font
					(size 1.27 1.27)
				)
			)
		)
		(property "Value" ""
			(at 0 0 0)
			(layer "F.Fab")
			(effects
				(font
					(size 1.27 1.27)
				)
			)
		)
		(duplicate_pad_numbers_are_jumpers no)
		(fp_line
			(start -0.32512 -0.175006)
			(end 0.32512 -0.175006)
			(stroke
				(width 0.1)
				(type default)
			)
			(layer "F.Fab")
		)
		(fp_line
			(start -0.32512 0.175006)
			(end -0.32512 -0.175006)
			(stroke
				(width 0.1)
				(type default)
			)
			(layer "F.Fab")
		)
		(fp_line
			(start 0.32512 -0.175006)
			(end 0.32512 0.175006)
			(stroke
				(width 0.1)
				(type default)
			)
			(layer "F.Fab")
		)
		(fp_line
			(start 0.32512 0.175006)
			(end -0.32512 0.175006)
			(stroke
				(width 0.1)
				(type default)
			)
			(layer "F.Fab")
		)
		(pad "1" smd rect
			(at -0.2667 0)
			(size 0.3048 0.381)
			(layers "F.Cu" "F.Mask" "F.Paste")
			(net "CLK_100M_RETIMER_CPU1_P1_R_DP")
		)
		(pad "2" smd rect
			(at 0.2667 0 180)
			(size 0.3048 0.381)
			(layers "F.Cu" "F.Mask" "F.Paste")
			(net "CLK_100M_RETIMER_CPU1_P1_DP")
		)
	)
	(footprint ""
		(layer "F.Cu")
		(at 239.50803 -48.019208 180)
		(property "Reference" "R3779"
			(at 0 0 180)
			(layer "F.SilkS")
			(hide yes)
			(effects
				(font
					(size 1.27 1.27)
				)
			)
		)
		(property "Value" ""
			(at 0 0 180)
			(layer "F.Fab")
			(effects
				(font
					(size 1.27 1.27)
				)
			)
		)
		(duplicate_pad_numbers_are_jumpers no)
		(fp_line
			(start 0.7874 0.4064)
			(end -0.7874 0.4064)
			(stroke
				(width 0.1524)
				(type default)
			)
			(layer "F.SilkS")
		)
		(fp_line
			(start 0.7874 -0.4064)
			(end 0.7874 0.4064)
			(stroke
				(width 0.1524)
				(type default)
			)
			(layer "F.SilkS")
		)
		(fp_line
			(start -0.7874 0.4064)
			(end -0.7874 -0.4064)
			(stroke
				(width 0.1524)
				(type default)
			)
			(layer "F.SilkS")
		)
		(fp_line
			(start -0.7874 -0.4064)
			(end 0.7874 -0.4064)
			(stroke
				(width 0.1524)
				(type default)
			)
			(layer "F.SilkS")
		)
		(fp_line
			(start 0.67945 0.3048)
			(end 0.120396 0.3048)
			(stroke
				(width 0.1)
				(type default)
			)
			(layer "F.Fab")
		)
		(fp_line
			(start 0.67945 -0.3048)
			(end 0.67945 0.3048)
			(stroke
				(width 0.1)
				(type default)
			)
			(layer "F.Fab")
		)
		(fp_line
			(start 0.12065 -0.2794)
			(end 0.12065 -0.3048)
			(stroke
				(width 0.1)
				(type default)
			)
			(layer "F.Fab")
		)
		(fp_line
			(start 0.12065 -0.3048)
			(end 0.67945 -0.3048)
			(stroke
				(width 0.1)
				(type default)
			)
			(layer "F.Fab")
		)
		(fp_line
			(start 0.120396 0.3048)
			(end 0.120396 0.2794)
			(stroke
				(width 0.1)
				(type default)
			)
			(layer "F.Fab")
		)
		(fp_line
			(start 0.120396 0.2794)
			(end -0.12065 0.2794)
			(stroke
				(width 0.1)
				(type default)
			)
			(layer "F.Fab")
		)
		(fp_line
			(start -0.12065 0.3048)
			(end -0.67945 0.3048)
			(stroke
				(width 0.1)
				(type default)
			)
			(layer "F.Fab")
		)
		(fp_line
			(start -0.12065 0.2794)
			(end -0.12065 0.3048)
			(stroke
				(width 0.1)
				(type default)
			)
			(layer "F.Fab")
		)
		(fp_line
			(start -0.12065 -0.2794)
			(end 0.12065 -0.2794)
			(stroke
				(width 0.1)
				(type default)
			)
			(layer "F.Fab")
		)
		(fp_line
			(start -0.12065 -0.305054)
			(end -0.12065 -0.2794)
			(stroke
				(width 0.1)
				(type default)
			)
			(layer "F.Fab")
		)
		(fp_line
			(start -0.67945 0.3048)
			(end -0.67945 -0.305054)
			(stroke
				(width 0.1)
				(type default)
			)
			(layer "F.Fab")
		)
		(fp_line
			(start -0.67945 -0.305054)
			(end -0.12065 -0.305054)
			(stroke
				(width 0.1)
				(type default)
			)
			(layer "F.Fab")
		)
		(pad "1" smd circle
			(at -0.40005 0 180)
			(size 0 0)
			(layers "F.Cu" "F.Mask" "F.Paste")
			(net "RST_PERST_E1S_0_N")
		)
		(pad "2" smd circle
			(at 0.40005 0 180)
			(size 0 0)
			(layers "F.Cu" "F.Mask" "F.Paste")
			(net "RST_PCIE_E1S_PERST_N")
		)
	)
)
